(kicad_pcb
	(version 20260206)
	(generator "pcbnew")
	(generator_version "10.0")
	(general
		(thickness 1.6)
		(legacy_teardrops no)
	)
	(paper "A4")
	(title_block
		(title "Bryce Canyon_IOM_M2_16342-2_OCP.brd")
		(comment 1 "Bryce Canyon / footprints 398-404 of 1146")
	)
	(layers
		(0 "F.Cu" signal "TOP")
		(4 "In1.Cu" signal "L2GND")
		(6 "In2.Cu" signal "L3")
		(8 "In3.Cu" signal "L4VCC")
		(10 "In4.Cu" signal "L5VCC")
		(12 "In5.Cu" signal "L6")
		(14 "In6.Cu" signal "L7GND")
		(2 "B.Cu" signal "BOTTOM")
		(9 "F.Adhes" user "F.Adhesive")
		(11 "B.Adhes" user "B.Adhesive")
		(13 "F.Paste" user "Package Geometry/Pastemask Top")
		(15 "B.Paste" user "Package Geometry/Pastemask Bottom")
		(5 "F.SilkS" user "Ref Des/Silkscreen Top")
		(7 "B.SilkS" user "Ref Des/Silkscreen Bottom")
		(1 "F.Mask" user "Board Geometry/Soldermask Top")
		(3 "B.Mask" user "Board Geometry/Soldermask Bottom")
		(17 "Dwgs.User" user "User.Drawings")
		(19 "Cmts.User" user "User.Comments")
		(21 "Eco1.User" user "User.Eco1")
		(23 "Eco2.User" user "User.Eco2")
		(25 "Edge.Cuts" user "Board Geometry/Outline")
		(27 "Margin" user)
		(31 "F.CrtYd" user "Package Geometry/Place Bound Top")
		(29 "B.CrtYd" user "Package Geometry/Place Bound Bottom")
		(35 "F.Fab" user "Ref Des/Assembly Top")
		(33 "B.Fab" user "Ref Des/Assembly Bottom")
	)
	(footprint ""
		(layer "F.Cu")
		(at 36.213288 -161.399728)
		(property "Reference" "R300"
			(at 0 0 0)
			(layer "F.SilkS")
			(hide yes)
			(effects
				(font
					(size 1.27 1.27)
				)
			)
		)
		(property "Value" "4K7R2F-GP"
			(at 0.064008 -3.993896 0)
			(unlocked yes)
			(layer "F.Fab")
			(hide yes)
			(effects
				(font
					(size 1.016 1.016)
					(thickness 0.1524)
				)
			)
		)
		(property "Device Type" "R402H16"
			(at 0.064008 -5.517896 0)
			(unlocked yes)
			(layer "F.Fab")
			(hide yes)
			(effects
				(font
					(size 1.016 1.016)
					(thickness 0.1524)
				)
			)
		)
		(duplicate_pad_numbers_are_jumpers no)
		(fp_line
			(start -0.508 -0.9398)
			(end -0.508 0.9398)
			(stroke
				(width 0.1524)
				(type default)
			)
			(layer "F.SilkS")
		)
		(fp_line
			(start 0.508 -0.9398)
			(end -0.508 -0.9398)
			(stroke
				(width 0.1524)
				(type default)
			)
			(layer "F.SilkS")
		)
		(fp_rect
			(start -0.508 0.9398)
			(end 0.508 -0.9398)
			(stroke
				(width 0)
				(type default)
			)
			(fill no)
			(layer "F.CrtYd")
		)
		(fp_rect
			(start -0.508 0.9398)
			(end 0.508 -0.9398)
			(stroke
				(width 0)
				(type default)
			)
			(fill no)
			(layer "F.Fab")
		)
		(pad "1" smd custom
			(at 0 -0.4445)
			(size 0.1397 0.1397)
			(layers "F.Cu" "F.Mask" "F.Paste")
			(net "P3V3_STBY")
			(options
				(clearance outline)
				(anchor circle)
			)
			(primitives
				(gr_poly
					(pts
						(arc
							(start -0.1778 -0.2794)
							(mid -0.249642 -0.249642)
							(end -0.2794 -0.1778)
						)
						(arc
							(start -0.2794 0.1778)
							(mid -0.249642 0.249642)
							(end -0.1778 0.2794)
						)
						(arc
							(start 0.1778 0.2794)
							(mid 0.249642 0.249642)
							(end 0.2794 0.1778)
						)
						(arc
							(start 0.2794 -0.1778)
							(mid 0.249642 -0.249642)
							(end 0.1778 -0.2794)
						)
					)
					(width 0)
					(fill yes)
				)
			)
		)
		(pad "2" smd custom
			(at 0 0.4445)
			(size 0.1397 0.1397)
			(layers "F.Cu" "F.Mask" "F.Paste")
			(net "UART_COMP_OUT_TX")
			(options
				(clearance outline)
				(anchor circle)
			)
			(primitives
				(gr_poly
					(pts
						(arc
							(start -0.1778 -0.2794)
							(mid -0.249642 -0.249642)
							(end -0.2794 -0.1778)
						)
						(arc
							(start -0.2794 0.1778)
							(mid -0.249642 0.249642)
							(end -0.1778 0.2794)
						)
						(arc
							(start 0.1778 0.2794)
							(mid 0.249642 0.249642)
							(end 0.2794 0.1778)
						)
						(arc
							(start 0.2794 -0.1778)
							(mid 0.249642 -0.249642)
							(end 0.1778 -0.2794)
						)
					)
					(width 0)
					(fill yes)
				)
			)
		)
	)
	(footprint ""
		(layer "F.Cu")
		(at 183.8452 -6.0198 180)
		(property "Reference" "R695"
			(at 0 0 180)
			(layer "F.SilkS")
			(hide yes)
			(effects
				(font
					(size 1.27 1.27)
				)
			)
		)
		(property "Value" "1KR2F-3-GP"
			(at 0.064008 -3.993896 180)
			(unlocked yes)
			(layer "F.Fab")
			(hide yes)
			(effects
				(font
					(size 1.016 1.016)
					(thickness 0.1524)
				)
			)
		)
		(property "Device Type" "R402H16"
			(at 0.064008 -5.517896 180)
			(unlocked yes)
			(layer "F.Fab")
			(hide yes)
			(effects
				(font
					(size 1.016 1.016)
					(thickness 0.1524)
				)
			)
		)
		(duplicate_pad_numbers_are_jumpers no)
		(fp_line
			(start 0.508 -0.9398)
			(end -0.508 -0.9398)
			(stroke
				(width 0.1524)
				(type default)
			)
			(layer "F.SilkS")
		)
		(fp_line
			(start -0.508 -0.9398)
			(end -0.508 0.9398)
			(stroke
				(width 0.1524)
				(type default)
			)
			(layer "F.SilkS")
		)
		(fp_rect
			(start -0.508 0.9398)
			(end 0.508 -0.9398)
			(stroke
				(width 0)
				(type default)
			)
			(fill no)
			(layer "F.CrtYd")
		)
		(fp_rect
			(start -0.508 0.9398)
			(end 0.508 -0.9398)
			(stroke
				(width 0)
				(type default)
			)
			(fill no)
			(layer "F.Fab")
		)
		(pad "1" smd custom
			(at 0 -0.4445 180)
			(size 0.1397 0.1397)
			(layers "F.Cu" "F.Mask" "F.Paste")
			(net "P5V_STBY")
			(options
				(clearance outline)
				(anchor circle)
			)
			(primitives
				(gr_poly
					(pts
						(arc
							(start -0.1778 -0.2794)
							(mid -0.249642 -0.249642)
							(end -0.2794 -0.1778)
						)
						(arc
							(start -0.2794 0.1778)
							(mid -0.249642 0.249642)
							(end -0.1778 0.2794)
						)
						(arc
							(start 0.1778 0.2794)
							(mid 0.249642 0.249642)
							(end 0.2794 0.1778)
						)
						(arc
							(start 0.2794 -0.1778)
							(mid 0.249642 -0.249642)
							(end 0.1778 -0.2794)
						)
					)
					(width 0)
					(fill yes)
				)
			)
		)
		(pad "2" smd custom
			(at 0 0.4445 180)
			(size 0.1397 0.1397)
			(layers "F.Cu" "F.Mask" "F.Paste")
			(net "BMC_ML_PWR_BLUE_LED_L")
			(options
				(clearance outline)
				(anchor circle)
			)
			(primitives
				(gr_poly
					(pts
						(arc
							(start -0.1778 -0.2794)
							(mid -0.249642 -0.249642)
							(end -0.2794 -0.1778)
						)
						(arc
							(start -0.2794 0.1778)
							(mid -0.249642 0.249642)
							(end -0.1778 0.2794)
						)
						(arc
							(start 0.1778 0.2794)
							(mid 0.249642 0.249642)
							(end 0.2794 0.1778)
						)
						(arc
							(start 0.2794 -0.1778)
							(mid 0.249642 -0.249642)
							(end 0.1778 -0.2794)
						)
					)
					(width 0)
					(fill yes)
				)
			)
		)
	)
	(footprint ""
		(layer "F.Cu")
		(at 45.932598 -117.795294 90)
		(property "Reference" "C36"
			(at 0 0 90)
			(layer "F.SilkS")
			(hide yes)
			(effects
				(font
					(size 1.27 1.27)
				)
			)
		)
		(property "Value" "SCD1U16V2KX-3GP"
			(at 1.1811 -2.7051 90)
			(unlocked yes)
			(layer "F.Fab")
			(hide yes)
			(effects
				(font
					(size 1.016 1.016)
					(thickness 0.1524)
				)
			)
		)
		(property "Device Type" "C402H22"
			(at 1.1811 -4.2291 90)
			(unlocked yes)
			(layer "F.Fab")
			(hide yes)
			(effects
				(font
					(size 1.016 1.016)
					(thickness 0.1524)
				)
			)
		)
		(duplicate_pad_numbers_are_jumpers no)
		(fp_rect
			(start -0.4318 0.9525)
			(end 0.4318 -0.9525)
			(stroke
				(width 0)
				(type default)
			)
			(fill no)
			(layer "F.CrtYd")
		)
		(fp_rect
			(start -0.4318 0.9525)
			(end 0.4318 -0.9525)
			(stroke
				(width 0)
				(type default)
			)
			(fill no)
			(layer "F.Fab")
		)
		(pad "1" smd custom
			(at 0 -0.4445 90)
			(size 0.1524 0.1524)
			(layers "F.Cu" "F.Mask" "F.Paste")
			(net "P3V3_STBY")
			(options
				(clearance outline)
				(anchor circle)
			)
			(primitives
				(gr_poly
					(pts
						(arc
							(start 0.3048 -0.2032)
							(mid 0.275042 -0.275042)
							(end 0.2032 -0.3048)
						)
						(arc
							(start -0.2032 -0.3048)
							(mid -0.275042 -0.275042)
							(end -0.3048 -0.2032)
						)
						(arc
							(start -0.3048 0.2032)
							(mid -0.275042 0.275042)
							(end -0.2032 0.3048)
						)
						(arc
							(start 0.2032 0.3048)
							(mid 0.275042 0.275042)
							(end 0.3048 0.2032)
						)
					)
					(width 0)
					(fill yes)
				)
			)
		)
		(pad "2" smd custom
			(at 0 0.4445 90)
			(size 0.1524 0.1524)
			(layers "F.Cu" "F.Mask" "F.Paste")
			(net "GND")
			(options
				(clearance outline)
				(anchor circle)
			)
			(primitives
				(gr_poly
					(pts
						(arc
							(start 0.3048 -0.2032)
							(mid 0.275042 -0.275042)
							(end 0.2032 -0.3048)
						)
						(arc
							(start -0.2032 -0.3048)
							(mid -0.275042 -0.275042)
							(end -0.3048 -0.2032)
						)
						(arc
							(start -0.3048 0.2032)
							(mid -0.275042 0.275042)
							(end -0.2032 0.3048)
						)
						(arc
							(start 0.2032 0.3048)
							(mid 0.275042 0.275042)
							(end 0.3048 0.2032)
						)
					)
					(width 0)
					(fill yes)
				)
			)
		)
	)
	(footprint ""
		(layer "F.Cu")
		(at 45.97019 -158.5976)
		(property "Reference" "R172"
			(at 0 0 0)
			(layer "F.SilkS")
			(hide yes)
			(effects
				(font
					(size 1.27 1.27)
				)
			)
		)
		(property "Value" "0R2J-2-GP"
			(at 0.064008 -3.993896 0)
			(unlocked yes)
			(layer "F.Fab")
			(hide yes)
			(effects
				(font
					(size 1.016 1.016)
					(thickness 0.1524)
				)
			)
		)
		(property "Device Type" "R402H16"
			(at 0.064008 -5.517896 0)
			(unlocked yes)
			(layer "F.Fab")
			(hide yes)
			(effects
				(font
					(size 1.016 1.016)
					(thickness 0.1524)
				)
			)
		)
		(duplicate_pad_numbers_are_jumpers no)
		(fp_line
			(start -0.508 -0.9398)
			(end -0.508 0.9398)
			(stroke
				(width 0.1524)
				(type default)
			)
			(layer "F.SilkS")
		)
		(fp_line
			(start 0.508 -0.9398)
			(end -0.508 -0.9398)
			(stroke
				(width 0.1524)
				(type default)
			)
			(layer "F.SilkS")
		)
		(fp_rect
			(start -0.508 0.9398)
			(end 0.508 -0.9398)
			(stroke
				(width 0)
				(type default)
			)
			(fill no)
			(layer "F.CrtYd")
		)
		(fp_rect
			(start -0.508 0.9398)
			(end 0.508 -0.9398)
			(stroke
				(width 0)
				(type default)
			)
			(fill no)
			(layer "F.Fab")
		)
		(pad "1" smd custom
			(at 0 -0.4445)
			(size 0.1397 0.1397)
			(layers "F.Cu" "F.Mask" "F.Paste")
			(net "I2C_DPB_SDA_OUT")
			(options
				(clearance outline)
				(anchor circle)
			)
			(primitives
				(gr_poly
					(pts
						(arc
							(start -0.1778 -0.2794)
							(mid -0.249642 -0.249642)
							(end -0.2794 -0.1778)
						)
						(arc
							(start -0.2794 0.1778)
							(mid -0.249642 0.249642)
							(end -0.1778 0.2794)
						)
						(arc
							(start 0.1778 0.2794)
							(mid 0.249642 0.249642)
							(end 0.2794 0.1778)
						)
						(arc
							(start 0.2794 -0.1778)
							(mid 0.249642 -0.249642)
							(end 0.1778 -0.2794)
						)
					)
					(width 0)
					(fill yes)
				)
			)
		)
		(pad "2" smd custom
			(at 0 0.4445)
			(size 0.1397 0.1397)
			(layers "F.Cu" "F.Mask" "F.Paste")
			(net "BMC_SMB7_DAT")
			(options
				(clearance outline)
				(anchor circle)
			)
			(primitives
				(gr_poly
					(pts
						(arc
							(start -0.1778 -0.2794)
							(mid -0.249642 -0.249642)
							(end -0.2794 -0.1778)
						)
						(arc
							(start -0.2794 0.1778)
							(mid -0.249642 0.249642)
							(end -0.1778 0.2794)
						)
						(arc
							(start 0.1778 0.2794)
							(mid 0.249642 0.249642)
							(end 0.2794 0.1778)
						)
						(arc
							(start 0.2794 -0.1778)
							(mid 0.249642 -0.249642)
							(end 0.1778 -0.2794)
						)
					)
					(width 0)
					(fill yes)
				)
			)
		)
	)
	(footprint ""
		(layer "F.Cu")
		(at 99.3648 -149.6314 -90)
		(property "Reference" "R30"
			(at 0 0 270)
			(layer "F.SilkS")
			(hide yes)
			(effects
				(font
					(size 1.27 1.27)
				)
			)
		)
		(property "Value" "4K7R2F-GP"
			(at 0.064008 -3.993896 270)
			(unlocked yes)
			(layer "F.Fab")
			(hide yes)
			(effects
				(font
					(size 1.016 1.016)
					(thickness 0.1524)
				)
			)
		)
		(property "Device Type" "R402H16"
			(at 0.064008 -5.517896 270)
			(unlocked yes)
			(layer "F.Fab")
			(hide yes)
			(effects
				(font
					(size 1.016 1.016)
					(thickness 0.1524)
				)
			)
		)
		(duplicate_pad_numbers_are_jumpers no)
		(fp_line
			(start -0.508 -0.9398)
			(end -0.508 0.9398)
			(stroke
				(width 0.1524)
				(type default)
			)
			(layer "F.SilkS")
		)
		(fp_line
			(start 0.508 -0.9398)
			(end -0.508 -0.9398)
			(stroke
				(width 0.1524)
				(type default)
			)
			(layer "F.SilkS")
		)
		(fp_rect
			(start -0.508 0.9398)
			(end 0.508 -0.9398)
			(stroke
				(width 0)
				(type default)
			)
			(fill no)
			(layer "F.CrtYd")
		)
		(fp_rect
			(start -0.508 0.9398)
			(end 0.508 -0.9398)
			(stroke
				(width 0)
				(type default)
			)
			(fill no)
			(layer "F.Fab")
		)
		(pad "1" smd custom
			(at 0 -0.4445 270)
			(size 0.1397 0.1397)
			(layers "F.Cu" "F.Mask" "F.Paste")
			(net "P3V3_STBY")
			(options
				(clearance outline)
				(anchor circle)
			)
			(primitives
				(gr_poly
					(pts
						(arc
							(start -0.1778 -0.2794)
							(mid -0.249642 -0.249642)
							(end -0.2794 -0.1778)
						)
						(arc
							(start -0.2794 0.1778)
							(mid -0.249642 0.249642)
							(end -0.1778 0.2794)
						)
						(arc
							(start 0.1778 0.2794)
							(mid 0.249642 0.249642)
							(end 0.2794 0.1778)
						)
						(arc
							(start 0.2794 -0.1778)
							(mid 0.249642 -0.249642)
							(end 0.1778 -0.2794)
						)
					)
					(width 0)
					(fill yes)
				)
			)
		)
		(pad "2" smd custom
			(at 0 0.4445 270)
			(size 0.1397 0.1397)
			(layers "F.Cu" "F.Mask" "F.Paste")
			(net "USB_OCS_N3")
			(options
				(clearance outline)
				(anchor circle)
			)
			(primitives
				(gr_poly
					(pts
						(arc
							(start -0.1778 -0.2794)
							(mid -0.249642 -0.249642)
							(end -0.2794 -0.1778)
						)
						(arc
							(start -0.2794 0.1778)
							(mid -0.249642 0.249642)
							(end -0.1778 0.2794)
						)
						(arc
							(start 0.1778 0.2794)
							(mid 0.249642 0.249642)
							(end 0.2794 0.1778)
						)
						(arc
							(start 0.2794 -0.1778)
							(mid 0.249642 -0.249642)
							(end 0.1778 -0.2794)
						)
					)
					(width 0)
					(fill yes)
				)
			)
		)
	)
	(footprint ""
		(layer "F.Cu")
		(at 165.629082 -133.555994 -90)
		(property "Reference" "R810"
			(at 0 0 270)
			(layer "F.SilkS")
			(hide yes)
			(effects
				(font
					(size 1.27 1.27)
				)
			)
		)
		(property "Value" "0R2J-2-GP"
			(at 0.064008 -3.993896 270)
			(unlocked yes)
			(layer "F.Fab")
			(hide yes)
			(effects
				(font
					(size 1.016 1.016)
					(thickness 0.1524)
				)
			)
		)
		(property "Device Type" "R402H16"
			(at 0.064008 -5.517896 270)
			(unlocked yes)
			(layer "F.Fab")
			(hide yes)
			(effects
				(font
					(size 1.016 1.016)
					(thickness 0.1524)
				)
			)
		)
		(duplicate_pad_numbers_are_jumpers no)
		(fp_line
			(start -0.508 -0.9398)
			(end -0.508 0.9398)
			(stroke
				(width 0.1524)
				(type default)
			)
			(layer "F.SilkS")
		)
		(fp_line
			(start 0.508 -0.9398)
			(end -0.508 -0.9398)
			(stroke
				(width 0.1524)
				(type default)
			)
			(layer "F.SilkS")
		)
		(fp_rect
			(start -0.508 0.9398)
			(end 0.508 -0.9398)
			(stroke
				(width 0)
				(type default)
			)
			(fill no)
			(layer "F.CrtYd")
		)
		(fp_rect
			(start -0.508 0.9398)
			(end 0.508 -0.9398)
			(stroke
				(width 0)
				(type default)
			)
			(fill no)
			(layer "F.Fab")
		)
		(pad "1" smd custom
			(at 0 -0.4445 270)
			(size 0.1397 0.1397)
			(layers "F.Cu" "F.Mask" "F.Paste")
			(net "M2_2_PRESENT_N")
			(options
				(clearance outline)
				(anchor circle)
			)
			(primitives
				(gr_poly
					(pts
						(arc
							(start -0.1778 -0.2794)
							(mid -0.249642 -0.249642)
							(end -0.2794 -0.1778)
						)
						(arc
							(start -0.2794 0.1778)
							(mid -0.249642 0.249642)
							(end -0.1778 0.2794)
						)
						(arc
							(start 0.1778 0.2794)
							(mid 0.249642 0.249642)
							(end 0.2794 0.1778)
						)
						(arc
							(start 0.2794 -0.1778)
							(mid 0.249642 -0.249642)
							(end 0.1778 -0.2794)
						)
					)
					(width 0)
					(fill yes)
				)
			)
		)
		(pad "2" smd custom
			(at 0 0.4445 270)
			(size 0.1397 0.1397)
			(layers "F.Cu" "F.Mask" "F.Paste")
			(net "M2_2_PRESENT_N_R")
			(options
				(clearance outline)
				(anchor circle)
			)
			(primitives
				(gr_poly
					(pts
						(arc
							(start -0.1778 -0.2794)
							(mid -0.249642 -0.249642)
							(end -0.2794 -0.1778)
						)
						(arc
							(start -0.2794 0.1778)
							(mid -0.249642 0.249642)
							(end -0.1778 0.2794)
						)
						(arc
							(start 0.1778 0.2794)
							(mid 0.249642 0.249642)
							(end 0.2794 0.1778)
						)
						(arc
							(start 0.2794 -0.1778)
							(mid 0.249642 -0.249642)
							(end 0.1778 -0.2794)
						)
					)
					(width 0)
					(fill yes)
				)
			)
		)
	)
	(footprint ""
		(layer "F.Cu")
		(at 50.4698 -131.7244)
		(property "Reference" "R149"
			(at 0 0 0)
			(layer "F.SilkS")
			(hide yes)
			(effects
				(font
					(size 1.27 1.27)
				)
			)
		)
		(property "Value" "100KR2F-L1-GP"
			(at 0.064008 -3.993896 0)
			(unlocked yes)
			(layer "F.Fab")
			(hide yes)
			(effects
				(font
					(size 1.016 1.016)
					(thickness 0.1524)
				)
			)
		)
		(property "Device Type" "R402H16"
			(at 0.064008 -5.517896 0)
			(unlocked yes)
			(layer "F.Fab")
			(hide yes)
			(effects
				(font
					(size 1.016 1.016)
					(thickness 0.1524)
				)
			)
		)
		(duplicate_pad_numbers_are_jumpers no)
		(fp_line
			(start -0.508 -0.9398)
			(end -0.508 0.9398)
			(stroke
				(width 0.1524)
				(type default)
			)
			(layer "F.SilkS")
		)
		(fp_line
			(start 0.508 -0.9398)
			(end -0.508 -0.9398)
			(stroke
				(width 0.1524)
				(type default)
			)
			(layer "F.SilkS")
		)
		(fp_rect
			(start -0.508 0.9398)
			(end 0.508 -0.9398)
			(stroke
				(width 0)
				(type default)
			)
			(fill no)
			(layer "F.CrtYd")
		)
		(fp_rect
			(start -0.508 0.9398)
			(end 0.508 -0.9398)
			(stroke
				(width 0)
				(type default)
			)
			(fill no)
			(layer "F.Fab")
		)
		(pad "1" smd custom
			(at 0 -0.4445)
			(size 0.1397 0.1397)
			(layers "F.Cu" "F.Mask" "F.Paste")
			(net "LPCRST0_N")
			(options
				(clearance outline)
				(anchor circle)
			)
			(primitives
				(gr_poly
					(pts
						(arc
							(start -0.1778 -0.2794)
							(mid -0.249642 -0.249642)
							(end -0.2794 -0.1778)
						)
						(arc
							(start -0.2794 0.1778)
							(mid -0.249642 0.249642)
							(end -0.1778 0.2794)
						)
						(arc
							(start 0.1778 0.2794)
							(mid 0.249642 0.249642)
							(end 0.2794 0.1778)
						)
						(arc
							(start 0.2794 -0.1778)
							(mid 0.249642 -0.249642)
							(end 0.1778 -0.2794)
						)
					)
					(width 0)
					(fill yes)
				)
			)
		)
		(pad "2" smd custom
			(at 0 0.4445)
			(size 0.1397 0.1397)
			(layers "F.Cu" "F.Mask" "F.Paste")
			(net "GND")
			(options
				(clearance outline)
				(anchor circle)
			)
			(primitives
				(gr_poly
					(pts
						(arc
							(start -0.1778 -0.2794)
							(mid -0.249642 -0.249642)
							(end -0.2794 -0.1778)
						)
						(arc
							(start -0.2794 0.1778)
							(mid -0.249642 0.249642)
							(end -0.1778 0.2794)
						)
						(arc
							(start 0.1778 0.2794)
							(mid 0.249642 0.249642)
							(end 0.2794 0.1778)
						)
						(arc
							(start 0.2794 -0.1778)
							(mid 0.249642 -0.249642)
							(end 0.1778 -0.2794)
						)
					)
					(width 0)
					(fill yes)
				)
			)
		)
	)
)
